# T6G (Grand Teton) — schematic netlist excerpt (pin names and nets, part order shuffled) for the footprints in the layout excerpt that follows; sources: Cadence DE-HDL packaged netlist, KiCad conversion of 04192023_DAF0TMB3IC0_F0TG_MB_C_brd_V02_OCP.brd

R3588  Q_RES  33.2 1% CHIP  pkg 0402LF  page 251 : A = SMB_INA230_3V3AUX_SCL ; B = SMB_INA230_2_3V3AUX_SCL_R
PL62  Q_INDUCTOR  0.22UH/33A IND  pkg SMLF  page 199 : \1\ = GND ; \2\ = IND_SOC_P0_CPL0
R8101  Q_RES  0 5% CHIP  pkg 0402LF  page 150 : A = FM_AC_PWR_BTN_R_N ; B = FM_AC_PWR_BTN_N

(kicad_pcb
	(version 20260206)
	(generator "pcbnew")
	(generator_version "10.0")
	(general
		(thickness 1.6)
		(legacy_teardrops no)
	)
	(paper "A4")
	(title_block
		(title "04192023_DAF0TMB3IC0_F0TG_MB_C_brd_V02_OCP.brd")
		(comment 1 "Grand Teton / footprints 4262-4264 of 8354")
	)
	(layers
		(0 "F.Cu" signal "TOP")
		(4 "In1.Cu" signal "GND")
		(6 "In2.Cu" signal "IN1")
		(8 "In3.Cu" signal "GND1")
		(10 "In4.Cu" signal "IN2")
		(12 "In5.Cu" signal "GND2")
		(14 "In6.Cu" signal "IN3")
		(16 "In7.Cu" signal "GND3")
		(18 "In8.Cu" signal "VCC")
		(20 "In9.Cu" signal "VCC1")
		(22 "In10.Cu" signal "GND4")
		(24 "In11.Cu" signal "IN4")
		(26 "In12.Cu" signal "GND5")
		(28 "In13.Cu" signal "IN5")
		(30 "In14.Cu" signal "GND6")
		(32 "In15.Cu" signal "IN6")
		(34 "In16.Cu" signal "GND7")
		(2 "B.Cu" signal "BOTTOM")
		(9 "F.Adhes" user "F.Adhesive")
		(11 "B.Adhes" user "B.Adhesive")
		(13 "F.Paste" user "Package Geometry/Pastemask Top")
		(15 "B.Paste" user "Package Geometry/Pastemask Bottom")
		(5 "F.SilkS" user "Ref Des/Silkscreen Top")
		(7 "B.SilkS" user "Ref Des/Silkscreen Bottom")
		(1 "F.Mask" user "Board Geometry/Soldermask Top")
		(3 "B.Mask" user "Board Geometry/Soldermask Bottom")
		(17 "Dwgs.User" user "User.Drawings")
		(19 "Cmts.User" user "User.Comments")
		(21 "Eco1.User" user "User.Eco1")
		(23 "Eco2.User" user "User.Eco2")
		(25 "Edge.Cuts" user "Board Geometry/Outline")
		(27 "Margin" user)
		(31 "F.CrtYd" user "Package Geometry/Place Bound Top")
		(29 "B.CrtYd" user "Package Geometry/Place Bound Bottom")
		(35 "F.Fab" user "Ref Des/Assembly Top")
		(33 "B.Fab" user "Ref Des/Assembly Bottom")
	)
	(footprint ""
		(layer "F.Cu")
		(at 146.927316 -21.498306 -90)
		(property "Reference" "R8101"
			(at 0 0 270)
			(layer "F.SilkS")
			(hide yes)
			(effects
				(font
					(size 1.27 1.27)
				)
			)
		)
		(property "Value" ""
			(at 0 0 270)
			(layer "F.Fab")
			(effects
				(font
					(size 1.27 1.27)
				)
			)
		)
		(duplicate_pad_numbers_are_jumpers no)
		(fp_line
			(start -0.7874 0.4064)
			(end -0.7874 -0.4064)
			(stroke
				(width 0.1524)
				(type default)
			)
			(layer "F.SilkS")
		)
		(fp_line
			(start 0.7874 0.4064)
			(end -0.7874 0.4064)
			(stroke
				(width 0.1524)
				(type default)
			)
			(layer "F.SilkS")
		)
		(fp_line
			(start -0.7874 -0.4064)
			(end 0.7874 -0.4064)
			(stroke
				(width 0.1524)
				(type default)
			)
			(layer "F.SilkS")
		)
		(fp_line
			(start 0.7874 -0.4064)
			(end 0.7874 0.4064)
			(stroke
				(width 0.1524)
				(type default)
			)
			(layer "F.SilkS")
		)
		(fp_line
			(start -0.67945 0.3048)
			(end -0.67945 -0.305054)
			(stroke
				(width 0.1)
				(type default)
			)
			(layer "F.Fab")
		)
		(fp_line
			(start -0.12065 0.3048)
			(end -0.67945 0.3048)
			(stroke
				(width 0.1)
				(type default)
			)
			(layer "F.Fab")
		)
		(fp_line
			(start 0.120396 0.3048)
			(end 0.120396 0.2794)
			(stroke
				(width 0.1)
				(type default)
			)
			(layer "F.Fab")
		)
		(fp_line
			(start 0.67945 0.3048)
			(end 0.120396 0.3048)
			(stroke
				(width 0.1)
				(type default)
			)
			(layer "F.Fab")
		)
		(fp_line
			(start -0.12065 0.2794)
			(end -0.12065 0.3048)
			(stroke
				(width 0.1)
				(type default)
			)
			(layer "F.Fab")
		)
		(fp_line
			(start 0.120396 0.2794)
			(end -0.12065 0.2794)
			(stroke
				(width 0.1)
				(type default)
			)
			(layer "F.Fab")
		)
		(fp_line
			(start -0.12065 -0.2794)
			(end 0.12065 -0.2794)
			(stroke
				(width 0.1)
				(type default)
			)
			(layer "F.Fab")
		)
		(fp_line
			(start 0.12065 -0.2794)
			(end 0.12065 -0.3048)
			(stroke
				(width 0.1)
				(type default)
			)
			(layer "F.Fab")
		)
		(fp_line
			(start 0.12065 -0.3048)
			(end 0.67945 -0.3048)
			(stroke
				(width 0.1)
				(type default)
			)
			(layer "F.Fab")
		)
		(fp_line
			(start 0.67945 -0.3048)
			(end 0.67945 0.3048)
			(stroke
				(width 0.1)
				(type default)
			)
			(layer "F.Fab")
		)
		(fp_line
			(start -0.67945 -0.305054)
			(end -0.12065 -0.305054)
			(stroke
				(width 0.1)
				(type default)
			)
			(layer "F.Fab")
		)
		(fp_line
			(start -0.12065 -0.305054)
			(end -0.12065 -0.2794)
			(stroke
				(width 0.1)
				(type default)
			)
			(layer "F.Fab")
		)
		(pad "1" smd circle
			(at -0.40005 0 270)
			(size 0 0)
			(layers "F.Cu" "F.Mask" "F.Paste")
			(net "FM_AC_PWR_BTN_R_N")
		)
		(pad "2" smd circle
			(at 0.40005 0 270)
			(size 0 0)
			(layers "F.Cu" "F.Mask" "F.Paste")
			(net "FM_AC_PWR_BTN_N")
		)
	)
	(footprint ""
		(layer "F.Cu")
		(at 422.688258 -171.231306 90)
		(property "Reference" "PL62"
			(at -3.10134 4.124452 90)
			(unlocked yes)
			(layer "F.SilkS")
			(effects
				(font
					(size 0.7874 0.5842)
					(thickness 0.1524)
				)
				(justify left)
			)
		)
		(property "Value" ""
			(at 0 0 90)
			(layer "F.Fab")
			(effects
				(font
					(size 1.27 1.27)
				)
			)
		)
		(duplicate_pad_numbers_are_jumpers no)
		(fp_line
			(start 3.24993 -3.24993)
			(end 3.24993 -2.2352)
			(stroke
				(width 0.1524)
				(type default)
			)
			(layer "F.SilkS")
		)
		(fp_line
			(start -3.24993 -3.24993)
			(end 3.24993 -3.24993)
			(stroke
				(width 0.1524)
				(type default)
			)
			(layer "F.SilkS")
		)
		(fp_line
			(start -3.24993 -2.2352)
			(end -3.24993 -3.24993)
			(stroke
				(width 0.1524)
				(type default)
			)
			(layer "F.SilkS")
		)
		(fp_line
			(start 3.24993 2.761742)
			(end 3.24993 3.24993)
			(stroke
				(width 0.1524)
				(type default)
			)
			(layer "F.SilkS")
		)
		(fp_line
			(start 3.24993 3.24993)
			(end -3.24993 3.24993)
			(stroke
				(width 0.1524)
				(type default)
			)
			(layer "F.SilkS")
		)
		(fp_line
			(start -3.24993 3.24993)
			(end -3.24993 2.2352)
			(stroke
				(width 0.1524)
				(type default)
			)
			(layer "F.SilkS")
		)
		(fp_line
			(start 3.24993 -3.24993)
			(end 3.24993 3.24993)
			(stroke
				(width 0.1)
				(type default)
			)
			(layer "F.Fab")
		)
		(fp_line
			(start -3.24993 -3.24993)
			(end 3.24993 -3.24993)
			(stroke
				(width 0.1)
				(type default)
			)
			(layer "F.Fab")
		)
		(fp_line
			(start 3.24993 3.24993)
			(end -3.24993 3.24993)
			(stroke
				(width 0.1)
				(type default)
			)
			(layer "F.Fab")
		)
		(fp_line
			(start -3.24993 3.24993)
			(end -3.24993 -3.24993)
			(stroke
				(width 0.1)
				(type default)
			)
			(layer "F.Fab")
		)
		(pad "1" smd rect
			(at -2.29997 0 90)
			(size 2.0066 4.2164)
			(layers "F.Cu" "F.Mask" "F.Paste")
			(net "GND")
		)
		(pad "2" smd rect
			(at 2.29997 0 90)
			(size 2.0066 4.2164)
			(layers "F.Cu" "F.Mask" "F.Paste")
			(net "IND_SOC_P0_CPL0")
		)
	)
	(footprint ""
		(layer "F.Cu")
		(at 214.432134 -47.335948 90)
		(property "Reference" "R3588"
			(at 0 0 90)
			(layer "F.SilkS")
			(hide yes)
			(effects
				(font
					(size 1.27 1.27)
				)
			)
		)
		(property "Value" ""
			(at 0 0 90)
			(layer "F.Fab")
			(effects
				(font
					(size 1.27 1.27)
				)
			)
		)
		(duplicate_pad_numbers_are_jumpers no)
		(fp_line
			(start 0.7874 -0.4064)
			(end 0.7874 0.4064)
			(stroke
				(width 0.1524)
				(type default)
			)
			(layer "F.SilkS")
		)
		(fp_line
			(start -0.7874 -0.4064)
			(end 0.7874 -0.4064)
			(stroke
				(width 0.1524)
				(type default)
			)
			(layer "F.SilkS")
		)
		(fp_line
			(start 0.7874 0.4064)
			(end -0.7874 0.4064)
			(stroke
				(width 0.1524)
				(type default)
			)
			(layer "F.SilkS")
		)
		(fp_line
			(start -0.7874 0.4064)
			(end -0.7874 -0.4064)
			(stroke
				(width 0.1524)
				(type default)
			)
			(layer "F.SilkS")
		)
		(fp_line
			(start -0.12065 -0.305054)
			(end -0.12065 -0.2794)
			(stroke
				(width 0.1)
				(type default)
			)
			(layer "F.Fab")
		)
		(fp_line
			(start -0.67945 -0.305054)
			(end -0.12065 -0.305054)
			(stroke
				(width 0.1)
				(type default)
			)
			(layer "F.Fab")
		)
		(fp_line
			(start 0.67945 -0.3048)
			(end 0.67945 0.3048)
			(stroke
				(width 0.1)
				(type default)
			)
			(layer "F.Fab")
		)
		(fp_line
			(start 0.12065 -0.3048)
			(end 0.67945 -0.3048)
			(stroke
				(width 0.1)
				(type default)
			)
			(layer "F.Fab")
		)
		(fp_line
			(start 0.12065 -0.2794)
			(end 0.12065 -0.3048)
			(stroke
				(width 0.1)
				(type default)
			)
			(layer "F.Fab")
		)
		(fp_line
			(start -0.12065 -0.2794)
			(end 0.12065 -0.2794)
			(stroke
				(width 0.1)
				(type default)
			)
			(layer "F.Fab")
		)
		(fp_line
			(start 0.120396 0.2794)
			(end -0.12065 0.2794)
			(stroke
				(width 0.1)
				(type default)
			)
			(layer "F.Fab")
		)
		(fp_line
			(start -0.12065 0.2794)
			(end -0.12065 0.3048)
			(stroke
				(width 0.1)
				(type default)
			)
			(layer "F.Fab")
		)
		(fp_line
			(start 0.67945 0.3048)
			(end 0.120396 0.3048)
			(stroke
				(width 0.1)
				(type default)
			)
			(layer "F.Fab")
		)
		(fp_line
			(start 0.120396 0.3048)
			(end 0.120396 0.2794)
			(stroke
				(width 0.1)
				(type default)
			)
			(layer "F.Fab")
		)
		(fp_line
			(start -0.12065 0.3048)
			(end -0.67945 0.3048)
			(stroke
				(width 0.1)
				(type default)
			)
			(layer "F.Fab")
		)
		(fp_line
			(start -0.67945 0.3048)
			(end -0.67945 -0.305054)
			(stroke
				(width 0.1)
				(type default)
			)
			(layer "F.Fab")
		)
		(pad "1" smd circle
			(at -0.40005 0 90)
			(size 0 0)
			(layers "F.Cu" "F.Mask" "F.Paste")
			(net "SMB_INA230_3V3AUX_SCL")
		)
		(pad "2" smd circle
			(at 0.40005 0 90)
			(size 0 0)
			(layers "F.Cu" "F.Mask" "F.Paste")
			(net "SMB_INA230_2_3V3AUX_SCL_R")
		)
	)
)
